# S9S_MB_2U (Grand Teton) — schematic netlist excerpt (pin names and nets, part order shuffled) for the footprints in the layout excerpt that follows; sources: Cadence DE-HDL packaged netlist, KiCad conversion of 03242023_DA0F0TMBIJ0_F0T_Motherboard_J_brd_V01_OCP.brd

R3656  Q_RES  10K 1% EMPTY  pkg 0402LF  page 152 : A = P3V3_AUX ; B = USB_HUB_OVCUR1
R1857  Q_RES  10K 1% CHIP  pkg 0402LF  page 242 : A = P3V3_AUX ; B = P12V_SCM_EN

(kicad_pcb
	(version 20260206)
	(generator "pcbnew")
	(generator_version "10.0")
	(general
		(thickness 1.6)
		(legacy_teardrops no)
	)
	(paper "A4")
	(title_block
		(title "03242023_DA0F0TMBIJ0_F0T_Motherboard_J_brd_V01_OCP.brd")
		(comment 1 "Grand Teton / footprints 3080-3081 of 6105")
	)
	(layers
		(0 "F.Cu" signal "TOP")
		(4 "In1.Cu" signal "GND")
		(6 "In2.Cu" signal "IN1")
		(8 "In3.Cu" signal "GND1")
		(10 "In4.Cu" signal "IN2")
		(12 "In5.Cu" signal "GND2")
		(14 "In6.Cu" signal "IN3")
		(16 "In7.Cu" signal "GND3")
		(18 "In8.Cu" signal "VCC")
		(20 "In9.Cu" signal "VCC1")
		(22 "In10.Cu" signal "GND4")
		(24 "In11.Cu" signal "IN4")
		(26 "In12.Cu" signal "GND5")
		(28 "In13.Cu" signal "IN5")
		(30 "In14.Cu" signal "GND6")
		(32 "In15.Cu" signal "IN6")
		(34 "In16.Cu" signal "GND7")
		(2 "B.Cu" signal "BOTTOM")
		(9 "F.Adhes" user "F.Adhesive")
		(11 "B.Adhes" user "B.Adhesive")
		(13 "F.Paste" user "Package Geometry/Pastemask Top")
		(15 "B.Paste" user "Package Geometry/Pastemask Bottom")
		(5 "F.SilkS" user "Ref Des/Silkscreen Top")
		(7 "B.SilkS" user "Ref Des/Silkscreen Bottom")
		(1 "F.Mask" user "Board Geometry/Soldermask Top")
		(3 "B.Mask" user "Board Geometry/Soldermask Bottom")
		(17 "Dwgs.User" user "User.Drawings")
		(19 "Cmts.User" user "User.Comments")
		(21 "Eco1.User" user "User.Eco1")
		(23 "Eco2.User" user "User.Eco2")
		(25 "Edge.Cuts" user "Board Geometry/Outline")
		(27 "Margin" user)
		(31 "F.CrtYd" user "Package Geometry/Place Bound Top")
		(29 "B.CrtYd" user "Package Geometry/Place Bound Bottom")
		(35 "F.Fab" user "Ref Des/Assembly Top")
		(33 "B.Fab" user "Ref Des/Assembly Bottom")
	)
	(footprint ""
		(layer "F.Cu")
		(at 197.180962 -39.046912)
		(property "Reference" "R1857"
			(at 0 0 0)
			(layer "F.SilkS")
			(hide yes)
			(effects
				(font
					(size 1.27 1.27)
				)
			)
		)
		(property "Value" ""
			(at 0 0 0)
			(layer "F.Fab")
			(effects
				(font
					(size 1.27 1.27)
				)
			)
		)
		(duplicate_pad_numbers_are_jumpers no)
		(fp_line
			(start -0.7874 -0.4064)
			(end 0.7874 -0.4064)
			(stroke
				(width 0.1524)
				(type default)
			)
			(layer "F.SilkS")
		)
		(fp_line
			(start -0.7874 0.4064)
			(end -0.7874 -0.4064)
			(stroke
				(width 0.1524)
				(type default)
			)
			(layer "F.SilkS")
		)
		(fp_line
			(start 0.7874 -0.4064)
			(end 0.7874 0.4064)
			(stroke
				(width 0.1524)
				(type default)
			)
			(layer "F.SilkS")
		)
		(fp_line
			(start 0.7874 0.4064)
			(end -0.7874 0.4064)
			(stroke
				(width 0.1524)
				(type default)
			)
			(layer "F.SilkS")
		)
		(fp_line
			(start -0.67945 -0.305054)
			(end -0.12065 -0.305054)
			(stroke
				(width 0.1)
				(type default)
			)
			(layer "F.Fab")
		)
		(fp_line
			(start -0.67945 0.3048)
			(end -0.67945 -0.305054)
			(stroke
				(width 0.1)
				(type default)
			)
			(layer "F.Fab")
		)
		(fp_line
			(start -0.12065 -0.305054)
			(end -0.12065 -0.2794)
			(stroke
				(width 0.1)
				(type default)
			)
			(layer "F.Fab")
		)
		(fp_line
			(start -0.12065 -0.2794)
			(end 0.12065 -0.2794)
			(stroke
				(width 0.1)
				(type default)
			)
			(layer "F.Fab")
		)
		(fp_line
			(start -0.12065 0.2794)
			(end -0.12065 0.3048)
			(stroke
				(width 0.1)
				(type default)
			)
			(layer "F.Fab")
		)
		(fp_line
			(start -0.12065 0.3048)
			(end -0.67945 0.3048)
			(stroke
				(width 0.1)
				(type default)
			)
			(layer "F.Fab")
		)
		(fp_line
			(start 0.120396 0.2794)
			(end -0.12065 0.2794)
			(stroke
				(width 0.1)
				(type default)
			)
			(layer "F.Fab")
		)
		(fp_line
			(start 0.120396 0.3048)
			(end 0.120396 0.2794)
			(stroke
				(width 0.1)
				(type default)
			)
			(layer "F.Fab")
		)
		(fp_line
			(start 0.12065 -0.3048)
			(end 0.67945 -0.3048)
			(stroke
				(width 0.1)
				(type default)
			)
			(layer "F.Fab")
		)
		(fp_line
			(start 0.12065 -0.2794)
			(end 0.12065 -0.3048)
			(stroke
				(width 0.1)
				(type default)
			)
			(layer "F.Fab")
		)
		(fp_line
			(start 0.67945 -0.3048)
			(end 0.67945 0.3048)
			(stroke
				(width 0.1)
				(type default)
			)
			(layer "F.Fab")
		)
		(fp_line
			(start 0.67945 0.3048)
			(end 0.120396 0.3048)
			(stroke
				(width 0.1)
				(type default)
			)
			(layer "F.Fab")
		)
		(pad "1" smd circle
			(at -0.40005 0)
			(size 0 0)
			(layers "F.Cu" "F.Mask" "F.Paste")
			(net "P3V3_AUX")
		)
		(pad "2" smd circle
			(at 0.40005 0)
			(size 0 0)
			(layers "F.Cu" "F.Mask" "F.Paste")
			(net "P12V_SCM_EN")
		)
	)
	(footprint ""
		(layer "F.Cu")
		(at 21.176996 -100.54971 180)
		(property "Reference" "R3656"
			(at 0 0 180)
			(layer "F.SilkS")
			(hide yes)
			(effects
				(font
					(size 1.27 1.27)
				)
			)
		)
		(property "Value" ""
			(at 0 0 180)
			(layer "F.Fab")
			(effects
				(font
					(size 1.27 1.27)
				)
			)
		)
		(duplicate_pad_numbers_are_jumpers no)
		(fp_line
			(start 0.7874 0.4064)
			(end -0.7874 0.4064)
			(stroke
				(width 0.1524)
				(type default)
			)
			(layer "F.SilkS")
		)
		(fp_line
			(start 0.7874 -0.4064)
			(end 0.7874 0.4064)
			(stroke
				(width 0.1524)
				(type default)
			)
			(layer "F.SilkS")
		)
		(fp_line
			(start -0.7874 0.4064)
			(end -0.7874 -0.4064)
			(stroke
				(width 0.1524)
				(type default)
			)
			(layer "F.SilkS")
		)
		(fp_line
			(start -0.7874 -0.4064)
			(end 0.7874 -0.4064)
			(stroke
				(width 0.1524)
				(type default)
			)
			(layer "F.SilkS")
		)
		(fp_line
			(start 0.67945 0.3048)
			(end 0.120396 0.3048)
			(stroke
				(width 0.1)
				(type default)
			)
			(layer "F.Fab")
		)
		(fp_line
			(start 0.67945 -0.3048)
			(end 0.67945 0.3048)
			(stroke
				(width 0.1)
				(type default)
			)
			(layer "F.Fab")
		)
		(fp_line
			(start 0.12065 -0.2794)
			(end 0.12065 -0.3048)
			(stroke
				(width 0.1)
				(type default)
			)
			(layer "F.Fab")
		)
		(fp_line
			(start 0.12065 -0.3048)
			(end 0.67945 -0.3048)
			(stroke
				(width 0.1)
				(type default)
			)
			(layer "F.Fab")
		)
		(fp_line
			(start 0.120396 0.3048)
			(end 0.120396 0.2794)
			(stroke
				(width 0.1)
				(type default)
			)
			(layer "F.Fab")
		)
		(fp_line
			(start 0.120396 0.2794)
			(end -0.12065 0.2794)
			(stroke
				(width 0.1)
				(type default)
			)
			(layer "F.Fab")
		)
		(fp_line
			(start -0.12065 0.3048)
			(end -0.67945 0.3048)
			(stroke
				(width 0.1)
				(type default)
			)
			(layer "F.Fab")
		)
		(fp_line
			(start -0.12065 0.2794)
			(end -0.12065 0.3048)
			(stroke
				(width 0.1)
				(type default)
			)
			(layer "F.Fab")
		)
		(fp_line
			(start -0.12065 -0.2794)
			(end 0.12065 -0.2794)
			(stroke
				(width 0.1)
				(type default)
			)
			(layer "F.Fab")
		)
		(fp_line
			(start -0.12065 -0.305054)
			(end -0.12065 -0.2794)
			(stroke
				(width 0.1)
				(type default)
			)
			(layer "F.Fab")
		)
		(fp_line
			(start -0.67945 0.3048)
			(end -0.67945 -0.305054)
			(stroke
				(width 0.1)
				(type default)
			)
			(layer "F.Fab")
		)
		(fp_line
			(start -0.67945 -0.305054)
			(end -0.12065 -0.305054)
			(stroke
				(width 0.1)
				(type default)
			)
			(layer "F.Fab")
		)
		(pad "1" smd circle
			(at -0.40005 0 180)
			(size 0 0)
			(layers "F.Cu" "F.Mask" "F.Paste")
			(net "P3V3_AUX")
		)
		(pad "2" smd circle
			(at 0.40005 0 180)
			(size 0 0)
			(layers "F.Cu" "F.Mask" "F.Paste")
			(net "USB_HUB_OVCUR1")
		)
	)
)
